# T6G (Grand Teton) — schematic netlist excerpt (pin names and nets, part order shuffled) for the footprints in the layout excerpt that follows; sources: Cadence DE-HDL packaged netlist, KiCad conversion of 04192023_DAF0TMB3IC0_F0TG_MB_C_brd_V02_OCP.brd

PC6553_1  Q_CAP  100NF 50V 10% X7R  pkg C0402  page 363 : A = PV09_RETIMER_CPU0_VCCS ; B = GND
PR8  Q_RES  8.66K 1% CHIP  pkg 0402LF  page 226 : A = PVDD18_S5_P1_CS ; B = GND
PC522  Q_CAPP  270UF 16V 20% OSCON  pkg THLF  page 225 : A = SW_P12V_AUX_PVDD11_S3_P1_FLT ; B = GND

(kicad_pcb
	(version 20260206)
	(generator "pcbnew")
	(generator_version "10.0")
	(general
		(thickness 1.6)
		(legacy_teardrops no)
	)
	(paper "A4")
	(title_block
		(title "04192023_DAF0TMB3IC0_F0TG_MB_C_brd_V02_OCP.brd")
		(comment 1 "Grand Teton / footprints 233-235 of 8354")
	)
	(layers
		(0 "F.Cu" signal "TOP")
		(4 "In1.Cu" signal "GND")
		(6 "In2.Cu" signal "IN1")
		(8 "In3.Cu" signal "GND1")
		(10 "In4.Cu" signal "IN2")
		(12 "In5.Cu" signal "GND2")
		(14 "In6.Cu" signal "IN3")
		(16 "In7.Cu" signal "GND3")
		(18 "In8.Cu" signal "VCC")
		(20 "In9.Cu" signal "VCC1")
		(22 "In10.Cu" signal "GND4")
		(24 "In11.Cu" signal "IN4")
		(26 "In12.Cu" signal "GND5")
		(28 "In13.Cu" signal "IN5")
		(30 "In14.Cu" signal "GND6")
		(32 "In15.Cu" signal "IN6")
		(34 "In16.Cu" signal "GND7")
		(2 "B.Cu" signal "BOTTOM")
		(9 "F.Adhes" user "F.Adhesive")
		(11 "B.Adhes" user "B.Adhesive")
		(13 "F.Paste" user "Package Geometry/Pastemask Top")
		(15 "B.Paste" user "Package Geometry/Pastemask Bottom")
		(5 "F.SilkS" user "Ref Des/Silkscreen Top")
		(7 "B.SilkS" user "Ref Des/Silkscreen Bottom")
		(1 "F.Mask" user "Board Geometry/Soldermask Top")
		(3 "B.Mask" user "Board Geometry/Soldermask Bottom")
		(17 "Dwgs.User" user "User.Drawings")
		(19 "Cmts.User" user "User.Comments")
		(21 "Eco1.User" user "User.Eco1")
		(23 "Eco2.User" user "User.Eco2")
		(25 "Edge.Cuts" user "Board Geometry/Outline")
		(27 "Margin" user)
		(31 "F.CrtYd" user "Package Geometry/Place Bound Top")
		(29 "B.CrtYd" user "Package Geometry/Place Bound Bottom")
		(35 "F.Fab" user "Ref Des/Assembly Top")
		(33 "B.Fab" user "Ref Des/Assembly Bottom")
	)
	(footprint ""
		(layer "F.Cu")
		(at 441.776866 -402.838412 90)
		(property "Reference" "PC6553_1"
			(at 0 0 90)
			(layer "F.SilkS")
			(hide yes)
			(effects
				(font
					(size 1.27 1.27)
				)
			)
		)
		(property "Value" ""
			(at 0 0 90)
			(layer "F.Fab")
			(effects
				(font
					(size 1.27 1.27)
				)
			)
		)
		(duplicate_pad_numbers_are_jumpers no)
		(fp_line
			(start 0.7874 -0.4064)
			(end 0.7874 0.4064)
			(stroke
				(width 0.1524)
				(type default)
			)
			(layer "F.SilkS")
		)
		(fp_line
			(start -0.7874 -0.4064)
			(end 0.7874 -0.4064)
			(stroke
				(width 0.1524)
				(type default)
			)
			(layer "F.SilkS")
		)
		(fp_line
			(start 0.7874 0.4064)
			(end -0.7874 0.4064)
			(stroke
				(width 0.1524)
				(type default)
			)
			(layer "F.SilkS")
		)
		(fp_line
			(start -0.7874 0.4064)
			(end -0.7874 -0.4064)
			(stroke
				(width 0.1524)
				(type default)
			)
			(layer "F.SilkS")
		)
		(fp_line
			(start -0.12065 -0.305054)
			(end -0.12065 -0.2794)
			(stroke
				(width 0.1)
				(type default)
			)
			(layer "F.Fab")
		)
		(fp_line
			(start -0.67945 -0.305054)
			(end -0.12065 -0.305054)
			(stroke
				(width 0.1)
				(type default)
			)
			(layer "F.Fab")
		)
		(fp_line
			(start 0.67945 -0.3048)
			(end 0.67945 0.3048)
			(stroke
				(width 0.1)
				(type default)
			)
			(layer "F.Fab")
		)
		(fp_line
			(start 0.12065 -0.3048)
			(end 0.67945 -0.3048)
			(stroke
				(width 0.1)
				(type default)
			)
			(layer "F.Fab")
		)
		(fp_line
			(start 0.12065 -0.2794)
			(end 0.12065 -0.3048)
			(stroke
				(width 0.1)
				(type default)
			)
			(layer "F.Fab")
		)
		(fp_line
			(start -0.12065 -0.2794)
			(end 0.12065 -0.2794)
			(stroke
				(width 0.1)
				(type default)
			)
			(layer "F.Fab")
		)
		(fp_line
			(start 0.120396 0.2794)
			(end -0.12065 0.2794)
			(stroke
				(width 0.1)
				(type default)
			)
			(layer "F.Fab")
		)
		(fp_line
			(start -0.12065 0.2794)
			(end -0.12065 0.3048)
			(stroke
				(width 0.1)
				(type default)
			)
			(layer "F.Fab")
		)
		(fp_line
			(start 0.67945 0.3048)
			(end 0.120396 0.3048)
			(stroke
				(width 0.1)
				(type default)
			)
			(layer "F.Fab")
		)
		(fp_line
			(start 0.120396 0.3048)
			(end 0.120396 0.2794)
			(stroke
				(width 0.1)
				(type default)
			)
			(layer "F.Fab")
		)
		(fp_line
			(start -0.12065 0.3048)
			(end -0.67945 0.3048)
			(stroke
				(width 0.1)
				(type default)
			)
			(layer "F.Fab")
		)
		(fp_line
			(start -0.67945 0.3048)
			(end -0.67945 -0.305054)
			(stroke
				(width 0.1)
				(type default)
			)
			(layer "F.Fab")
		)
		(pad "1" smd circle
			(at -0.40005 0 90)
			(size 0 0)
			(layers "F.Cu" "F.Mask" "F.Paste")
			(net "PV09_RETIMER_CPU0_VCCS")
		)
		(pad "2" smd circle
			(at 0.40005 0 90)
			(size 0 0)
			(layers "F.Cu" "F.Mask" "F.Paste")
			(net "GND")
		)
	)
	(footprint ""
		(layer "F.Cu")
		(at 191.67983 -362.430568 180)
		(property "Reference" "PC522"
			(at -1.14554 -2.774188 0)
			(unlocked yes)
			(layer "F.SilkS")
			(effects
				(font
					(size 0.7874 0.5842)
					(thickness 0.1524)
				)
				(justify left)
			)
		)
		(property "Value" ""
			(at 0 0 180)
			(layer "F.Fab")
			(effects
				(font
					(size 1.27 1.27)
				)
			)
		)
		(duplicate_pad_numbers_are_jumpers no)
		(fp_line
			(start -3.400044 1.249934)
			(end 3.400044 1.249934)
			(stroke
				(width 0.1524)
				(type default)
			)
			(layer "F.SilkS")
		)
		(fp_circle
			(center 0 1.249934)
			(end -3.400044 1.249934)
			(stroke
				(width 0.1524)
				(type default)
			)
			(fill no)
			(layer "F.SilkS")
		)
		(fp_poly
			(pts
				(arc
					(start 3.400044 1.249934)
					(mid 0 4.649978)
					(end -3.400044 1.249934)
				)
			)
			(stroke
				(width 0)
				(type default)
			)
			(fill yes)
			(layer "F.SilkS")
		)
		(fp_circle
			(center 0 1.249934)
			(end -3.400044 1.249934)
			(stroke
				(width 0.1)
				(type default)
			)
			(fill no)
			(layer "F.Fab")
		)
		(pad "1" thru_hole rect
			(at 0 0 180)
			(size 1.524 1.524)
			(drill 1.016)
			(layers "*.Cu" "*.Mask")
			(remove_unused_layers no)
			(net "SW_P12V_AUX_PVDD11_S3_P1_FLT")
			(clearance 0)
			(padstack
				(mode front_inner_back)
				(layer "Inner"
					(shape circle)
					(size 1.524 1.524)
					(clearance 0)
				)
				(layer "B.Cu"
					(shape rect)
					(size 1.524 1.524)
					(clearance 0)
				)
			)
		)
		(pad "2" thru_hole circle
			(at 0 2.500122 180)
			(size 1.524 1.524)
			(drill 1.016)
			(layers "*.Cu" "*.Mask")
			(remove_unused_layers no)
			(net "GND")
			(clearance 0)
		)
	)
	(footprint ""
		(layer "F.Cu")
		(at 68.42887 -148.21789 -90)
		(property "Reference" "PR8"
			(at 0 0 270)
			(layer "F.SilkS")
			(hide yes)
			(effects
				(font
					(size 1.27 1.27)
				)
			)
		)
		(property "Value" ""
			(at 0 0 270)
			(layer "F.Fab")
			(effects
				(font
					(size 1.27 1.27)
				)
			)
		)
		(duplicate_pad_numbers_are_jumpers no)
		(fp_line
			(start -0.7874 0.4064)
			(end -0.7874 -0.4064)
			(stroke
				(width 0.1524)
				(type default)
			)
			(layer "F.SilkS")
		)
		(fp_line
			(start 0.7874 0.4064)
			(end -0.7874 0.4064)
			(stroke
				(width 0.1524)
				(type default)
			)
			(layer "F.SilkS")
		)
		(fp_line
			(start -0.7874 -0.4064)
			(end 0.7874 -0.4064)
			(stroke
				(width 0.1524)
				(type default)
			)
			(layer "F.SilkS")
		)
		(fp_line
			(start 0.7874 -0.4064)
			(end 0.7874 0.4064)
			(stroke
				(width 0.1524)
				(type default)
			)
			(layer "F.SilkS")
		)
		(fp_line
			(start -0.67945 0.3048)
			(end -0.67945 -0.305054)
			(stroke
				(width 0.1)
				(type default)
			)
			(layer "F.Fab")
		)
		(fp_line
			(start -0.12065 0.3048)
			(end -0.67945 0.3048)
			(stroke
				(width 0.1)
				(type default)
			)
			(layer "F.Fab")
		)
		(fp_line
			(start 0.120396 0.3048)
			(end 0.120396 0.2794)
			(stroke
				(width 0.1)
				(type default)
			)
			(layer "F.Fab")
		)
		(fp_line
			(start 0.67945 0.3048)
			(end 0.120396 0.3048)
			(stroke
				(width 0.1)
				(type default)
			)
			(layer "F.Fab")
		)
		(fp_line
			(start -0.12065 0.2794)
			(end -0.12065 0.3048)
			(stroke
				(width 0.1)
				(type default)
			)
			(layer "F.Fab")
		)
		(fp_line
			(start 0.120396 0.2794)
			(end -0.12065 0.2794)
			(stroke
				(width 0.1)
				(type default)
			)
			(layer "F.Fab")
		)
		(fp_line
			(start -0.12065 -0.2794)
			(end 0.12065 -0.2794)
			(stroke
				(width 0.1)
				(type default)
			)
			(layer "F.Fab")
		)
		(fp_line
			(start 0.12065 -0.2794)
			(end 0.12065 -0.3048)
			(stroke
				(width 0.1)
				(type default)
			)
			(layer "F.Fab")
		)
		(fp_line
			(start 0.12065 -0.3048)
			(end 0.67945 -0.3048)
			(stroke
				(width 0.1)
				(type default)
			)
			(layer "F.Fab")
		)
		(fp_line
			(start 0.67945 -0.3048)
			(end 0.67945 0.3048)
			(stroke
				(width 0.1)
				(type default)
			)
			(layer "F.Fab")
		)
		(fp_line
			(start -0.67945 -0.305054)
			(end -0.12065 -0.305054)
			(stroke
				(width 0.1)
				(type default)
			)
			(layer "F.Fab")
		)
		(fp_line
			(start -0.12065 -0.305054)
			(end -0.12065 -0.2794)
			(stroke
				(width 0.1)
				(type default)
			)
			(layer "F.Fab")
		)
		(pad "1" smd circle
			(at -0.40005 0 270)
			(size 0 0)
			(layers "F.Cu" "F.Mask" "F.Paste")
			(net "PVDD18_S5_P1_CS")
		)
		(pad "2" smd circle
			(at 0.40005 0 270)
			(size 0 0)
			(layers "F.Cu" "F.Mask" "F.Paste")
			(net "GND")
		)
	)
)
